(kicad_pcb
	(version 20241229)
	(generator "pcbnew")
	(generator_version "9.0")
	(general
		(thickness 1.6296)
		(legacy_teardrops no)
	)
	(paper "A3")
	(title_block
		(title "Thunderbolt to 10GbE adapter")
		(date "2026-04-21")
		(rev "1.1.0")
		(company "Antmicro Ltd")
		(comment 1 "www.antmicro.com")
		(comment 9 "footprints 700-703 of 703")
	)
	(layers
		(0 "F.Cu" signal)
		(4 "In1.Cu" signal)
		(6 "In2.Cu" signal)
		(8 "In3.Cu" signal)
		(10 "In4.Cu" signal)
		(12 "In5.Cu" signal)
		(14 "In6.Cu" signal)
		(2 "B.Cu" signal)
		(9 "F.Adhes" user "F.Adhesive")
		(11 "B.Adhes" user "B.Adhesive")
		(13 "F.Paste" user)
		(15 "B.Paste" user)
		(5 "F.SilkS" user "F.Silkscreen")
		(7 "B.SilkS" user "B.Silkscreen")
		(1 "F.Mask" user)
		(3 "B.Mask" user)
		(17 "Dwgs.User" user "User.Drawings")
		(19 "Cmts.User" user "User.Comments")
		(21 "Eco1.User" user "User.Eco1")
		(23 "Eco2.User" user "User.Eco2")
		(25 "Edge.Cuts" user)
		(27 "Margin" user)
		(31 "F.CrtYd" user "F.Courtyard")
		(29 "B.CrtYd" user "B.Courtyard")
		(35 "F.Fab" user)
		(33 "B.Fab" user)
	)
	(footprint "antmicro-footprints:C_0402_1005Metric"
		(layer "B.Cu")
		(at 145.631866 80.260117 180)
		(descr "Capacitor SMD 0402")
		(tags "capacitor SMD 0402")
		(property "Reference" "C240"
			(at -17.768134 -9.464883 0)
			(layer "B.SilkS")
			(effects
				(font
					(size 0.7 0.7)
					(thickness 0.15)
				)
				(justify mirror)
			)
		)
		(property "Value" "C_1u_25V_0402"
			(at -1.022927 -2.155213 0)
			(layer "B.Fab")
			(effects
				(font
					(size 0.7 0.7)
					(thickness 0.15)
				)
				(justify left bottom mirror)
			)
		)
		(property "Datasheet" "https://www.murata.com/products/productdetail?partno=GRM155R61E105KE11%23"
			(at 0 0 0)
			(layer "B.Fab")
			(hide yes)
			(effects
				(font
					(size 1.27 1.27)
					(thickness 0.15)
				)
				(justify mirror)
			)
		)
		(property "Description" "SMD Multilayer Ceramic Capacitor, 1 µF, 25 V, 0402 [1005 Metric], ± 10%, X5R, GRM Series"
			(at 0 0 0)
			(layer "B.Fab")
			(hide yes)
			(effects
				(font
					(size 1.27 1.27)
					(thickness 0.15)
				)
				(justify mirror)
			)
		)
		(property "MPN" "GRM155R61E105KE11J"
			(at 0 0 180)
			(unlocked yes)
			(layer "B.Fab")
			(hide yes)
			(effects
				(font
					(size 1 1)
					(thickness 0.15)
				)
				(justify mirror)
			)
		)
		(property "Manufacturer" "Murata"
			(at 0 0 180)
			(unlocked yes)
			(layer "B.Fab")
			(hide yes)
			(effects
				(font
					(size 1 1)
					(thickness 0.15)
				)
				(justify mirror)
			)
		)
		(property "License" "Apache-2.0"
			(at 0 0 180)
			(unlocked yes)
			(layer "B.Fab")
			(hide yes)
			(effects
				(font
					(size 1 1)
					(thickness 0.15)
				)
				(justify mirror)
			)
		)
		(property "Author" "Antmicro"
			(at 0 0 180)
			(unlocked yes)
			(layer "B.Fab")
			(hide yes)
			(effects
				(font
					(size 1 1)
					(thickness 0.15)
				)
				(justify mirror)
			)
		)
		(property "Val" "1u"
			(at 0 0 180)
			(unlocked yes)
			(layer "B.Fab")
			(hide yes)
			(effects
				(font
					(size 1 1)
					(thickness 0.15)
				)
				(justify mirror)
			)
		)
		(property "Voltage" "25V"
			(at 0 0 180)
			(unlocked yes)
			(layer "B.Fab")
			(hide yes)
			(effects
				(font
					(size 1 1)
					(thickness 0.15)
				)
				(justify mirror)
			)
		)
		(property "Dielectric" "X5R"
			(at 0 0 180)
			(unlocked yes)
			(layer "B.Fab")
			(hide yes)
			(effects
				(font
					(size 1 1)
					(thickness 0.15)
				)
				(justify mirror)
			)
		)
		(sheetname "/X710-AT2 power/")
		(sheetfile "x710-at2-power.kicad_sch")
		(attr smd)
		(fp_rect
			(start -0.925 0.47)
			(end 0.925 -0.47)
			(stroke
				(width 0.05)
				(type default)
			)
			(fill no)
			(layer "B.CrtYd")
		)
		(fp_line
			(start 0.504 0.25)
			(end 0.504 -0.248)
			(stroke
				(width 0.15)
				(type solid)
			)
			(layer "B.Fab")
		)
		(fp_line
			(start 0.504 -0.248)
			(end -0.494 -0.248)
			(stroke
				(width 0.15)
				(type solid)
			)
			(layer "B.Fab")
		)
		(fp_line
			(start -0.494 0.25)
			(end 0.504 0.25)
			(stroke
				(width 0.15)
				(type solid)
			)
			(layer "B.Fab")
		)
		(fp_line
			(start -0.494 -0.248)
			(end -0.494 0.25)
			(stroke
				(width 0.15)
				(type solid)
			)
			(layer "B.Fab")
		)
		(fp_text user "${REFERENCE}"
			(at -0.939 -4.599 0)
			(layer "B.Fab")
			(effects
				(font
					(size 0.7 0.7)
					(thickness 0.15)
				)
				(justify left bottom mirror)
			)
		)
		(fp_text user "License: Apache-2.0"
			(at -0.939 -5.799 0)
			(layer "B.Fab")
			(effects
				(font
					(size 0.7 0.7)
					(thickness 0.15)
				)
				(justify left bottom mirror)
			)
		)
		(fp_text user "Author: Antmicro"
			(at -0.939 -3.399 0)
			(layer "B.Fab")
			(effects
				(font
					(size 0.7 0.7)
					(thickness 0.15)
				)
				(justify left bottom mirror)
			)
		)
		(pad "1" smd roundrect
			(at -0.48 0 180)
			(size 0.59 0.64)
			(layers "B.Cu" "B.Mask" "B.Paste")
			(roundrect_rratio 0.25)
			(net 23 "GND")
			(pintype "passive")
		)
		(pad "2" smd roundrect
			(at 0.48 0 180)
			(size 0.59 0.64)
			(layers "B.Cu" "B.Mask" "B.Paste")
			(roundrect_rratio 0.25)
			(net 1 "VCCA")
			(pintype "passive")
		)
	)
	(footprint "antmicro-footprints:TP_SMD_0.75mm"
		(layer "B.Cu")
		(at 148.9 91 180)
		(property "Reference" "TP36"
			(at -18.1 -10.500001 0)
			(layer "B.SilkS")
			(effects
				(font
					(size 0.7 0.7)
					(thickness 0.15)
				)
				(justify mirror)
			)
		)
		(property "Value" "TP_0.75mm_SMD"
			(at 0 -1.2 0)
			(layer "B.Fab")
			(effects
				(font
					(size 0.7 0.7)
					(thickness 0.15)
				)
				(justify left bottom mirror)
			)
		)
		(property "Description" "SMT test point"
			(at 0 0 0)
			(layer "B.Fab")
			(hide yes)
			(effects
				(font
					(size 1.27 1.27)
					(thickness 0.15)
				)
				(justify mirror)
			)
		)
		(property "MPN" ""
			(at 0 0 180)
			(unlocked yes)
			(layer "B.Fab")
			(hide yes)
			(effects
				(font
					(size 1 1)
					(thickness 0.15)
				)
				(justify mirror)
			)
		)
		(property "Manufacturer" ""
			(at 0 0 180)
			(unlocked yes)
			(layer "B.Fab")
			(hide yes)
			(effects
				(font
					(size 1 1)
					(thickness 0.15)
				)
				(justify mirror)
			)
		)
		(property "Author" "Antmicro"
			(at 0 0 180)
			(unlocked yes)
			(layer "B.Fab")
			(hide yes)
			(effects
				(font
					(size 1 1)
					(thickness 0.15)
				)
				(justify mirror)
			)
		)
		(property "License" "Apache-2.0"
			(at 0 0 180)
			(unlocked yes)
			(layer "B.Fab")
			(hide yes)
			(effects
				(font
					(size 1 1)
					(thickness 0.15)
				)
				(justify mirror)
			)
		)
		(sheetname "/X710-AT2 Misc/")
		(sheetfile "x710-at2-mics.kicad_sch")
		(attr exclude_from_pos_files exclude_from_bom)
		(fp_circle
			(center 0 0)
			(end 0.475 0)
			(stroke
				(width 0.05)
				(type default)
			)
			(fill no)
			(layer "B.CrtYd")
		)
		(fp_text user "Author: Antmicro"
			(at -0.4 -3.901 0)
			(layer "B.Fab")
			(effects
				(font
					(size 0.7 0.7)
					(thickness 0.15)
				)
				(justify left bottom mirror)
			)
		)
		(fp_text user "${REFERENCE}"
			(at -0.4 -2.7 0)
			(layer "B.Fab")
			(effects
				(font
					(size 0.7 0.7)
					(thickness 0.15)
				)
				(justify left bottom mirror)
			)
		)
		(fp_text user "License: Apache-2.0"
			(at -0.4 -5.101 0)
			(layer "B.Fab")
			(effects
				(font
					(size 0.7 0.7)
					(thickness 0.15)
				)
				(justify left bottom mirror)
			)
		)
		(pad "1" smd circle
			(at 0 0 180)
			(size 0.75 0.75)
			(layers "B.Cu" "B.Mask")
			(net 445 "Net-(U14D-SMBD)")
			(pinfunction "1")
			(pintype "passive")
		)
	)
	(footprint "antmicro-footprints:R_0402_1005Metric"
		(layer "B.Cu")
		(at 118.5 89.75 90)
		(descr "Resistor SMD 0402")
		(tags "resistor SMD 0402")
		(property "Reference" "R75"
			(at -5.85 0.3 270)
			(layer "B.SilkS")
			(effects
				(font
					(size 0.7 0.7)
					(thickness 0.15)
				)
				(justify left bottom mirror)
			)
		)
		(property "Value" "R_8k2_0402"
			(at -1.011843 -1.772047 270)
			(layer "B.Fab")
			(effects
				(font
					(size 0.7 0.7)
					(thickness 0.15)
				)
				(justify left bottom mirror)
			)
		)
		(property "Datasheet" "https://www.bourns.com/docs/product-datasheets/cr.pdf"
			(at 0 0 270)
			(layer "B.Fab")
			(hide yes)
			(effects
				(font
					(size 1.27 1.27)
					(thickness 0.15)
				)
				(justify mirror)
			)
		)
		(property "Description" "SMD Chip Resistor"
			(at 0 0 270)
			(layer "B.Fab")
			(hide yes)
			(effects
				(font
					(size 1.27 1.27)
					(thickness 0.15)
				)
				(justify mirror)
			)
		)
		(property "MPN" "CR0402-FX-8201GLF"
			(at 0 0 90)
			(unlocked yes)
			(layer "B.Fab")
			(hide yes)
			(effects
				(font
					(size 1 1)
					(thickness 0.15)
				)
				(justify mirror)
			)
		)
		(property "Manufacturer" "Bourns"
			(at 0 0 90)
			(unlocked yes)
			(layer "B.Fab")
			(hide yes)
			(effects
				(font
					(size 1 1)
					(thickness 0.15)
				)
				(justify mirror)
			)
		)
		(property "License" "Apache-2.0"
			(at 0 0 90)
			(unlocked yes)
			(layer "B.Fab")
			(hide yes)
			(effects
				(font
					(size 1 1)
					(thickness 0.15)
				)
				(justify mirror)
			)
		)
		(property "Author" "Antmicro"
			(at 0 0 90)
			(unlocked yes)
			(layer "B.Fab")
			(hide yes)
			(effects
				(font
					(size 1 1)
					(thickness 0.15)
				)
				(justify mirror)
			)
		)
		(property "Val" "8k2"
			(at 0 0 90)
			(unlocked yes)
			(layer "B.Fab")
			(hide yes)
			(effects
				(font
					(size 1 1)
					(thickness 0.15)
				)
				(justify mirror)
			)
		)
		(property "Tolerance" "1%"
			(at 0 0 90)
			(unlocked yes)
			(layer "B.Fab")
			(hide yes)
			(effects
				(font
					(size 1 1)
					(thickness 0.15)
				)
				(justify mirror)
			)
		)
		(sheetname "/TB Controller - Power/")
		(sheetfile "tb-power.kicad_sch")
		(attr smd)
		(fp_rect
			(start -0.925 0.47)
			(end 0.925 -0.47)
			(stroke
				(width 0.05)
				(type default)
			)
			(fill no)
			(layer "B.CrtYd")
		)
		(fp_rect
			(start -0.5 0.25)
			(end 0.5 -0.25)
			(stroke
				(width 0.15)
				(type solid)
			)
			(fill no)
			(layer "B.Fab")
		)
		(fp_text user "License: Apache-2.0"
			(at -0.95 -5.169 270)
			(layer "B.Fab")
			(effects
				(font
					(size 0.7 0.7)
					(thickness 0.15)
				)
				(justify left bottom mirror)
			)
		)
		(fp_text user "Author: Antmicro"
			(at -0.95 -4.169 270)
			(layer "B.Fab")
			(effects
				(font
					(size 0.7 0.7)
					(thickness 0.15)
				)
				(justify left bottom mirror)
			)
		)
		(fp_text user "${REFERENCE}"
			(at -0.95 -3.168 270)
			(layer "B.Fab")
			(effects
				(font
					(size 0.7 0.7)
					(thickness 0.15)
				)
				(justify left bottom mirror)
			)
		)
		(pad "1" smd roundrect
			(at -0.48 0 90)
			(size 0.59 0.64)
			(layers "B.Cu" "B.Mask" "B.Paste")
			(roundrect_rratio 0.25)
			(net 435 "Net-(R75-Pad1)")
			(pintype "passive")
		)
		(pad "2" smd roundrect
			(at 0.48 0 90)
			(size 0.59 0.64)
			(layers "B.Cu" "B.Mask" "B.Paste")
			(roundrect_rratio 0.25)
			(net 57 "+3V3_TB")
			(pintype "passive")
		)
	)
	(footprint "antmicro-footprints:C_0402_1005Metric"
		(layer "B.Cu")
		(at 149.331866 78.260118 180)
		(descr "Capacitor SMD 0402")
		(tags "capacitor SMD 0402")
		(property "Reference" "C246"
			(at -19.468135 -9.464883 0)
			(layer "B.SilkS")
			(effects
				(font
					(size 0.7 0.7)
					(thickness 0.15)
				)
				(justify mirror)
			)
		)
		(property "Value" "C_1u_25V_0402"
			(at -1.022927 -2.155213 0)
			(layer "B.Fab")
			(effects
				(font
					(size 0.7 0.7)
					(thickness 0.15)
				)
				(justify left bottom mirror)
			)
		)
		(property "Datasheet" "https://www.murata.com/products/productdetail?partno=GRM155R61E105KE11%23"
			(at 0 0 0)
			(layer "B.Fab")
			(hide yes)
			(effects
				(font
					(size 1.27 1.27)
					(thickness 0.15)
				)
				(justify mirror)
			)
		)
		(property "Description" "SMD Multilayer Ceramic Capacitor, 1 µF, 25 V, 0402 [1005 Metric], ± 10%, X5R, GRM Series"
			(at 0 0 0)
			(layer "B.Fab")
			(hide yes)
			(effects
				(font
					(size 1.27 1.27)
					(thickness 0.15)
				)
				(justify mirror)
			)
		)
		(property "MPN" "GRM155R61E105KE11J"
			(at 0 0 180)
			(unlocked yes)
			(layer "B.Fab")
			(hide yes)
			(effects
				(font
					(size 1 1)
					(thickness 0.15)
				)
				(justify mirror)
			)
		)
		(property "Manufacturer" "Murata"
			(at 0 0 180)
			(unlocked yes)
			(layer "B.Fab")
			(hide yes)
			(effects
				(font
					(size 1 1)
					(thickness 0.15)
				)
				(justify mirror)
			)
		)
		(property "License" "Apache-2.0"
			(at 0 0 180)
			(unlocked yes)
			(layer "B.Fab")
			(hide yes)
			(effects
				(font
					(size 1 1)
					(thickness 0.15)
				)
				(justify mirror)
			)
		)
		(property "Author" "Antmicro"
			(at 0 0 180)
			(unlocked yes)
			(layer "B.Fab")
			(hide yes)
			(effects
				(font
					(size 1 1)
					(thickness 0.15)
				)
				(justify mirror)
			)
		)
		(property "Val" "1u"
			(at 0 0 180)
			(unlocked yes)
			(layer "B.Fab")
			(hide yes)
			(effects
				(font
					(size 1 1)
					(thickness 0.15)
				)
				(justify mirror)
			)
		)
		(property "Voltage" "25V"
			(at 0 0 180)
			(unlocked yes)
			(layer "B.Fab")
			(hide yes)
			(effects
				(font
					(size 1 1)
					(thickness 0.15)
				)
				(justify mirror)
			)
		)
		(property "Dielectric" "X5R"
			(at 0 0 180)
			(unlocked yes)
			(layer "B.Fab")
			(hide yes)
			(effects
				(font
					(size 1 1)
					(thickness 0.15)
				)
				(justify mirror)
			)
		)
		(sheetname "/X710-AT2 power/")
		(sheetfile "x710-at2-power.kicad_sch")
		(attr smd)
		(fp_rect
			(start -0.925 0.47)
			(end 0.925 -0.47)
			(stroke
				(width 0.05)
				(type default)
			)
			(fill no)
			(layer "B.CrtYd")
		)
		(fp_line
			(start 0.504 0.25)
			(end 0.504 -0.248)
			(stroke
				(width 0.15)
				(type solid)
			)
			(layer "B.Fab")
		)
		(fp_line
			(start 0.504 -0.248)
			(end -0.494 -0.248)
			(stroke
				(width 0.15)
				(type solid)
			)
			(layer "B.Fab")
		)
		(fp_line
			(start -0.494 0.25)
			(end 0.504 0.25)
			(stroke
				(width 0.15)
				(type solid)
			)
			(layer "B.Fab")
		)
		(fp_line
			(start -0.494 -0.248)
			(end -0.494 0.25)
			(stroke
				(width 0.15)
				(type solid)
			)
			(layer "B.Fab")
		)
		(fp_text user "License: Apache-2.0"
			(at -0.939 -5.799 0)
			(layer "B.Fab")
			(effects
				(font
					(size 0.7 0.7)
					(thickness 0.15)
				)
				(justify left bottom mirror)
			)
		)
		(fp_text user "${REFERENCE}"
			(at -0.939 -4.599 0)
			(layer "B.Fab")
			(effects
				(font
					(size 0.7 0.7)
					(thickness 0.15)
				)
				(justify left bottom mirror)
			)
		)
		(fp_text user "Author: Antmicro"
			(at -0.939 -3.399 0)
			(layer "B.Fab")
			(effects
				(font
					(size 0.7 0.7)
					(thickness 0.15)
				)
				(justify left bottom mirror)
			)
		)
		(pad "1" smd roundrect
			(at -0.48 0 180)
			(size 0.59 0.64)
			(layers "B.Cu" "B.Mask" "B.Paste")
			(roundrect_rratio 0.25)
			(net 23 "GND")
			(pintype "passive")
		)
		(pad "2" smd roundrect
			(at 0.48 0 180)
			(size 0.59 0.64)
			(layers "B.Cu" "B.Mask" "B.Paste")
			(roundrect_rratio 0.25)
			(net 9 "VCCD")
			(pintype "passive")
		)
	)
)
